# T6G (Grand Teton) — schematic netlist excerpt (pin names and nets, part order shuffled) for the footprints in the layout excerpt that follows; sources: Cadence DE-HDL packaged netlist, KiCad conversion of 04192023_DAF0TMB3IC0_F0TG_MB_C_brd_V02_OCP.brd

R203  Q_RES  0 5% CHIP  pkg 0402LF  page 81 : A = PWRGD_CPU1_PWROK ; B = FM_PWRGD_CPU1_PWROK
R5236  Q_RES  0 5% CHIP  pkg 0402LF  page 234 : A = USB2_HUB_BUF_SWB_R_DN ; B = USB2_HUB_BUF_SWB_DN
C389  Q_CAP  1UF 4V 20% X6S  pkg 0201  page 345 : A = P0V9_CPU1_RT2_2A ; B = GND

(kicad_pcb
	(version 20260206)
	(generator "pcbnew")
	(generator_version "10.0")
	(general
		(thickness 1.6)
		(legacy_teardrops no)
	)
	(paper "A4")
	(title_block
		(title "04192023_DAF0TMB3IC0_F0TG_MB_C_brd_V02_OCP.brd")
		(comment 1 "Grand Teton / footprints 7729-7731 of 8354")
	)
	(layers
		(0 "F.Cu" signal "TOP")
		(4 "In1.Cu" signal "GND")
		(6 "In2.Cu" signal "IN1")
		(8 "In3.Cu" signal "GND1")
		(10 "In4.Cu" signal "IN2")
		(12 "In5.Cu" signal "GND2")
		(14 "In6.Cu" signal "IN3")
		(16 "In7.Cu" signal "GND3")
		(18 "In8.Cu" signal "VCC")
		(20 "In9.Cu" signal "VCC1")
		(22 "In10.Cu" signal "GND4")
		(24 "In11.Cu" signal "IN4")
		(26 "In12.Cu" signal "GND5")
		(28 "In13.Cu" signal "IN5")
		(30 "In14.Cu" signal "GND6")
		(32 "In15.Cu" signal "IN6")
		(34 "In16.Cu" signal "GND7")
		(2 "B.Cu" signal "BOTTOM")
		(9 "F.Adhes" user "F.Adhesive")
		(11 "B.Adhes" user "B.Adhesive")
		(13 "F.Paste" user "Package Geometry/Pastemask Top")
		(15 "B.Paste" user "Package Geometry/Pastemask Bottom")
		(5 "F.SilkS" user "Ref Des/Silkscreen Top")
		(7 "B.SilkS" user "Ref Des/Silkscreen Bottom")
		(1 "F.Mask" user "Board Geometry/Soldermask Top")
		(3 "B.Mask" user "Board Geometry/Soldermask Bottom")
		(17 "Dwgs.User" user "User.Drawings")
		(19 "Cmts.User" user "User.Comments")
		(21 "Eco1.User" user "User.Eco1")
		(23 "Eco2.User" user "User.Eco2")
		(25 "Edge.Cuts" user "Board Geometry/Outline")
		(27 "Margin" user)
		(31 "F.CrtYd" user "Package Geometry/Place Bound Top")
		(29 "B.CrtYd" user "Package Geometry/Place Bound Bottom")
		(35 "F.Fab" user "Ref Des/Assembly Top")
		(33 "B.Fab" user "Ref Des/Assembly Bottom")
	)
	(footprint ""
		(layer "B.Cu")
		(at 150.606252 -386.766562 90)
		(property "Reference" "C389"
			(at 0 0 90)
			(layer "B.SilkS")
			(hide yes)
			(effects
				(font
					(size 1.27 1.27)
				)
				(justify mirror)
			)
		)
		(property "Value" ""
			(at 0 0 90)
			(layer "B.Fab")
			(effects
				(font
					(size 1.27 1.27)
				)
				(justify mirror)
			)
		)
		(duplicate_pad_numbers_are_jumpers no)
		(fp_line
			(start 0.299974 -0.150114)
			(end -0.299974 -0.150114)
			(stroke
				(width 0.1)
				(type default)
			)
			(layer "B.Fab")
		)
		(fp_line
			(start -0.299974 -0.150114)
			(end -0.299974 0.150114)
			(stroke
				(width 0.1)
				(type default)
			)
			(layer "B.Fab")
		)
		(fp_line
			(start 0.299974 0.150114)
			(end 0.299974 -0.150114)
			(stroke
				(width 0.1)
				(type default)
			)
			(layer "B.Fab")
		)
		(fp_line
			(start -0.299974 0.150114)
			(end 0.299974 0.150114)
			(stroke
				(width 0.1)
				(type default)
			)
			(layer "B.Fab")
		)
		(pad "1" smd rect
			(at 0.2667 0 270)
			(size 0.3048 0.381)
			(layers "B.Cu" "B.Mask" "B.Paste")
			(net "P0V9_CPU1_RT2_2A")
		)
		(pad "2" smd rect
			(at -0.2667 0 270)
			(size 0.3048 0.381)
			(layers "B.Cu" "B.Mask" "B.Paste")
			(net "GND")
		)
	)
	(footprint ""
		(layer "B.Cu")
		(at 50.718974 -419.723316 180)
		(property "Reference" "R5236"
			(at 0 0 0)
			(layer "B.SilkS")
			(hide yes)
			(effects
				(font
					(size 1.27 1.27)
				)
				(justify mirror)
			)
		)
		(property "Value" ""
			(at 0 0 0)
			(layer "B.Fab")
			(effects
				(font
					(size 1.27 1.27)
				)
				(justify mirror)
			)
		)
		(duplicate_pad_numbers_are_jumpers no)
		(fp_line
			(start 0.7874 0.4064)
			(end 0.7874 -0.4064)
			(stroke
				(width 0.1524)
				(type default)
			)
			(layer "B.SilkS")
		)
		(fp_line
			(start 0.7874 -0.4064)
			(end -0.7874 -0.4064)
			(stroke
				(width 0.1524)
				(type default)
			)
			(layer "B.SilkS")
		)
		(fp_line
			(start -0.7874 0.4064)
			(end 0.7874 0.4064)
			(stroke
				(width 0.1524)
				(type default)
			)
			(layer "B.SilkS")
		)
		(fp_line
			(start -0.7874 -0.4064)
			(end -0.7874 0.4064)
			(stroke
				(width 0.1524)
				(type default)
			)
			(layer "B.SilkS")
		)
		(fp_line
			(start 0.67945 0.3048)
			(end 0.67945 -0.305054)
			(stroke
				(width 0.1)
				(type default)
			)
			(layer "B.Fab")
		)
		(fp_line
			(start 0.67945 -0.305054)
			(end 0.12065 -0.305054)
			(stroke
				(width 0.1)
				(type default)
			)
			(layer "B.Fab")
		)
		(fp_line
			(start 0.12065 0.3048)
			(end 0.67945 0.3048)
			(stroke
				(width 0.1)
				(type default)
			)
			(layer "B.Fab")
		)
		(fp_line
			(start 0.12065 0.2794)
			(end 0.12065 0.3048)
			(stroke
				(width 0.1)
				(type default)
			)
			(layer "B.Fab")
		)
		(fp_line
			(start 0.12065 -0.2794)
			(end -0.12065 -0.2794)
			(stroke
				(width 0.1)
				(type default)
			)
			(layer "B.Fab")
		)
		(fp_line
			(start 0.12065 -0.305054)
			(end 0.12065 -0.2794)
			(stroke
				(width 0.1)
				(type default)
			)
			(layer "B.Fab")
		)
		(fp_line
			(start -0.120396 0.3048)
			(end -0.120396 0.2794)
			(stroke
				(width 0.1)
				(type default)
			)
			(layer "B.Fab")
		)
		(fp_line
			(start -0.120396 0.2794)
			(end 0.12065 0.2794)
			(stroke
				(width 0.1)
				(type default)
			)
			(layer "B.Fab")
		)
		(fp_line
			(start -0.12065 -0.2794)
			(end -0.12065 -0.3048)
			(stroke
				(width 0.1)
				(type default)
			)
			(layer "B.Fab")
		)
		(fp_line
			(start -0.12065 -0.3048)
			(end -0.67945 -0.3048)
			(stroke
				(width 0.1)
				(type default)
			)
			(layer "B.Fab")
		)
		(fp_line
			(start -0.67945 0.3048)
			(end -0.120396 0.3048)
			(stroke
				(width 0.1)
				(type default)
			)
			(layer "B.Fab")
		)
		(fp_line
			(start -0.67945 -0.3048)
			(end -0.67945 0.3048)
			(stroke
				(width 0.1)
				(type default)
			)
			(layer "B.Fab")
		)
		(pad "1" smd circle
			(at 0.40005 0)
			(size 0 0)
			(layers "B.Cu" "B.Mask" "B.Paste")
			(net "USB2_HUB_BUF_SWB_R_DN")
		)
		(pad "2" smd circle
			(at -0.40005 0)
			(size 0 0)
			(layers "B.Cu" "B.Mask" "B.Paste")
			(net "USB2_HUB_BUF_SWB_DN")
		)
	)
	(footprint ""
		(layer "B.Cu")
		(at 180.681376 -133.053328 90)
		(property "Reference" "R203"
			(at 0 0 90)
			(layer "B.SilkS")
			(hide yes)
			(effects
				(font
					(size 1.27 1.27)
				)
				(justify mirror)
			)
		)
		(property "Value" ""
			(at 0 0 90)
			(layer "B.Fab")
			(effects
				(font
					(size 1.27 1.27)
				)
				(justify mirror)
			)
		)
		(duplicate_pad_numbers_are_jumpers no)
		(fp_line
			(start 0.7874 -0.4064)
			(end -0.7874 -0.4064)
			(stroke
				(width 0.1524)
				(type default)
			)
			(layer "B.SilkS")
		)
		(fp_line
			(start -0.7874 -0.4064)
			(end -0.7874 0.4064)
			(stroke
				(width 0.1524)
				(type default)
			)
			(layer "B.SilkS")
		)
		(fp_line
			(start 0.7874 0.4064)
			(end 0.7874 -0.4064)
			(stroke
				(width 0.1524)
				(type default)
			)
			(layer "B.SilkS")
		)
		(fp_line
			(start -0.7874 0.4064)
			(end 0.7874 0.4064)
			(stroke
				(width 0.1524)
				(type default)
			)
			(layer "B.SilkS")
		)
		(fp_line
			(start 0.67945 -0.305054)
			(end 0.12065 -0.305054)
			(stroke
				(width 0.1)
				(type default)
			)
			(layer "B.Fab")
		)
		(fp_line
			(start 0.12065 -0.305054)
			(end 0.12065 -0.2794)
			(stroke
				(width 0.1)
				(type default)
			)
			(layer "B.Fab")
		)
		(fp_line
			(start -0.12065 -0.3048)
			(end -0.67945 -0.3048)
			(stroke
				(width 0.1)
				(type default)
			)
			(layer "B.Fab")
		)
		(fp_line
			(start -0.67945 -0.3048)
			(end -0.67945 0.3048)
			(stroke
				(width 0.1)
				(type default)
			)
			(layer "B.Fab")
		)
		(fp_line
			(start 0.12065 -0.2794)
			(end -0.12065 -0.2794)
			(stroke
				(width 0.1)
				(type default)
			)
			(layer "B.Fab")
		)
		(fp_line
			(start -0.12065 -0.2794)
			(end -0.12065 -0.3048)
			(stroke
				(width 0.1)
				(type default)
			)
			(layer "B.Fab")
		)
		(fp_line
			(start 0.12065 0.2794)
			(end 0.12065 0.3048)
			(stroke
				(width 0.1)
				(type default)
			)
			(layer "B.Fab")
		)
		(fp_line
			(start -0.120396 0.2794)
			(end 0.12065 0.2794)
			(stroke
				(width 0.1)
				(type default)
			)
			(layer "B.Fab")
		)
		(fp_line
			(start 0.67945 0.3048)
			(end 0.67945 -0.305054)
			(stroke
				(width 0.1)
				(type default)
			)
			(layer "B.Fab")
		)
		(fp_line
			(start 0.12065 0.3048)
			(end 0.67945 0.3048)
			(stroke
				(width 0.1)
				(type default)
			)
			(layer "B.Fab")
		)
		(fp_line
			(start -0.120396 0.3048)
			(end -0.120396 0.2794)
			(stroke
				(width 0.1)
				(type default)
			)
			(layer "B.Fab")
		)
		(fp_line
			(start -0.67945 0.3048)
			(end -0.120396 0.3048)
			(stroke
				(width 0.1)
				(type default)
			)
			(layer "B.Fab")
		)
		(pad "1" smd circle
			(at 0.40005 0 270)
			(size 0 0)
			(layers "B.Cu" "B.Mask" "B.Paste")
			(net "PWRGD_CPU1_PWROK")
		)
		(pad "2" smd circle
			(at -0.40005 0 270)
			(size 0 0)
			(layers "B.Cu" "B.Mask" "B.Paste")
			(net "FM_PWRGD_CPU1_PWROK")
		)
	)
)
